(kicad_pcb
	(version 20260206)
	(generator "pcbnew")
	(generator_version "10.0")
	(general
		(thickness 1.6)
		(legacy_teardrops no)
	)
	(paper "A4")
	(title_block
		(title "01162023_DA0F0TEBIF0_F0T_Expander_BD_F_brd_V02_OCP.brd")
		(comment 1 "Grand Teton / footprints 335-340 of 9728")
	)
	(layers
		(0 "F.Cu" signal "TOP")
		(4 "In1.Cu" signal "GND")
		(6 "In2.Cu" signal "VCC")
		(8 "In3.Cu" signal "VCC1")
		(10 "In4.Cu" signal "GND1")
		(12 "In5.Cu" signal "IN1")
		(14 "In6.Cu" signal "GND2")
		(16 "In7.Cu" signal "IN2")
		(18 "In8.Cu" signal "GND3")
		(20 "In9.Cu" signal "IN3")
		(22 "In10.Cu" signal "GND4")
		(24 "In11.Cu" signal "IN4")
		(26 "In12.Cu" signal "GND5")
		(28 "In13.Cu" signal "IN5")
		(30 "In14.Cu" signal "GND6")
		(32 "In15.Cu" signal "IN6")
		(34 "In16.Cu" signal "GND7")
		(2 "B.Cu" signal "BOTTOM")
		(9 "F.Adhes" user "F.Adhesive")
		(11 "B.Adhes" user "B.Adhesive")
		(13 "F.Paste" user "Package Geometry/Pastemask Top")
		(15 "B.Paste" user "Package Geometry/Pastemask Bottom")
		(5 "F.SilkS" user "Ref Des/Silkscreen Top")
		(7 "B.SilkS" user "Ref Des/Silkscreen Bottom")
		(1 "F.Mask" user "Board Geometry/Soldermask Top")
		(3 "B.Mask" user "Board Geometry/Soldermask Bottom")
		(17 "Dwgs.User" user "User.Drawings")
		(19 "Cmts.User" user "User.Comments")
		(21 "Eco1.User" user "User.Eco1")
		(23 "Eco2.User" user "User.Eco2")
		(25 "Edge.Cuts" user "Board Geometry/Outline")
		(27 "Margin" user)
		(31 "F.CrtYd" user "Package Geometry/Place Bound Top")
		(29 "B.CrtYd" user "Package Geometry/Place Bound Bottom")
		(35 "F.Fab" user "Ref Des/Assembly Top")
		(33 "B.Fab" user "Ref Des/Assembly Bottom")
	)
	(footprint ""
		(layer "F.Cu")
		(at 108.412788 -308.56809 -90)
		(property "Reference" "C4199"
			(at 0 0 270)
			(layer "F.SilkS")
			(hide yes)
			(effects
				(font
					(size 1.27 1.27)
				)
			)
		)
		(property "Value" ""
			(at 0 0 270)
			(layer "F.Fab")
			(effects
				(font
					(size 1.27 1.27)
				)
			)
		)
		(duplicate_pad_numbers_are_jumpers no)
		(fp_line
			(start -1.2954 0.5842)
			(end -1.2954 -0.5842)
			(stroke
				(width 0.1524)
				(type default)
			)
			(layer "F.SilkS")
		)
		(fp_line
			(start 1.2954 0.5842)
			(end -1.2954 0.5842)
			(stroke
				(width 0.1524)
				(type default)
			)
			(layer "F.SilkS")
		)
		(fp_line
			(start -1.2954 -0.5842)
			(end 1.2954 -0.5842)
			(stroke
				(width 0.1524)
				(type default)
			)
			(layer "F.SilkS")
		)
		(fp_line
			(start 1.2954 -0.5842)
			(end 1.2954 0.5842)
			(stroke
				(width 0.1524)
				(type default)
			)
			(layer "F.SilkS")
		)
		(fp_line
			(start -0.8636 0.4572)
			(end -0.8636 0.4064)
			(stroke
				(width 0.1)
				(type default)
			)
			(layer "F.Fab")
		)
		(fp_line
			(start 0.8636 0.4572)
			(end -0.8636 0.4572)
			(stroke
				(width 0.1)
				(type default)
			)
			(layer "F.Fab")
		)
		(fp_line
			(start -1.1938 0.4064)
			(end -1.1938 -0.4064)
			(stroke
				(width 0.1)
				(type default)
			)
			(layer "F.Fab")
		)
		(fp_line
			(start -0.8636 0.4064)
			(end -1.1938 0.4064)
			(stroke
				(width 0.1)
				(type default)
			)
			(layer "F.Fab")
		)
		(fp_line
			(start 0.8636 0.4064)
			(end 0.8636 0.4572)
			(stroke
				(width 0.1)
				(type default)
			)
			(layer "F.Fab")
		)
		(fp_line
			(start 1.1938 0.4064)
			(end 0.8636 0.4064)
			(stroke
				(width 0.1)
				(type default)
			)
			(layer "F.Fab")
		)
		(fp_line
			(start -1.1938 -0.4064)
			(end -0.8636 -0.4064)
			(stroke
				(width 0.1)
				(type default)
			)
			(layer "F.Fab")
		)
		(fp_line
			(start -0.8636 -0.4064)
			(end -0.8636 -0.4572)
			(stroke
				(width 0.1)
				(type default)
			)
			(layer "F.Fab")
		)
		(fp_line
			(start 0.8636 -0.4064)
			(end 1.1938 -0.4064)
			(stroke
				(width 0.1)
				(type default)
			)
			(layer "F.Fab")
		)
		(fp_line
			(start 1.1938 -0.4064)
			(end 1.1938 0.4064)
			(stroke
				(width 0.1)
				(type default)
			)
			(layer "F.Fab")
		)
		(fp_line
			(start -0.8636 -0.4572)
			(end 0.8636 -0.4572)
			(stroke
				(width 0.1)
				(type default)
			)
			(layer "F.Fab")
		)
		(fp_line
			(start 0.8636 -0.4572)
			(end 0.8636 -0.4064)
			(stroke
				(width 0.1)
				(type default)
			)
			(layer "F.Fab")
		)
		(pad "1" smd rect
			(at -0.7366 0 180)
			(size 0.7112 0.8128)
			(layers "F.Cu" "F.Mask" "F.Paste")
			(net "P0V8_PEX0")
		)
		(pad "2" smd rect
			(at 0.7366 0 180)
			(size 0.7112 0.8128)
			(layers "F.Cu" "F.Mask" "F.Paste")
			(net "GND")
		)
	)
	(footprint ""
		(layer "F.Cu")
		(at 208.487264 -300.650402 -90)
		(property "Reference" "R3932"
			(at 0 0 270)
			(layer "F.SilkS")
			(hide yes)
			(effects
				(font
					(size 1.27 1.27)
				)
			)
		)
		(property "Value" ""
			(at 0 0 270)
			(layer "F.Fab")
			(effects
				(font
					(size 1.27 1.27)
				)
			)
		)
		(duplicate_pad_numbers_are_jumpers no)
		(fp_line
			(start -0.7874 0.4064)
			(end -0.7874 -0.4064)
			(stroke
				(width 0.1524)
				(type default)
			)
			(layer "F.SilkS")
		)
		(fp_line
			(start 0.7874 0.4064)
			(end -0.7874 0.4064)
			(stroke
				(width 0.1524)
				(type default)
			)
			(layer "F.SilkS")
		)
		(fp_line
			(start -0.7874 -0.4064)
			(end 0.7874 -0.4064)
			(stroke
				(width 0.1524)
				(type default)
			)
			(layer "F.SilkS")
		)
		(fp_line
			(start 0.7874 -0.4064)
			(end 0.7874 0.4064)
			(stroke
				(width 0.1524)
				(type default)
			)
			(layer "F.SilkS")
		)
		(fp_line
			(start -0.67945 0.3048)
			(end -0.67945 -0.305054)
			(stroke
				(width 0.1)
				(type default)
			)
			(layer "F.Fab")
		)
		(fp_line
			(start -0.12065 0.3048)
			(end -0.67945 0.3048)
			(stroke
				(width 0.1)
				(type default)
			)
			(layer "F.Fab")
		)
		(fp_line
			(start 0.120396 0.3048)
			(end 0.120396 0.2794)
			(stroke
				(width 0.1)
				(type default)
			)
			(layer "F.Fab")
		)
		(fp_line
			(start 0.67945 0.3048)
			(end 0.120396 0.3048)
			(stroke
				(width 0.1)
				(type default)
			)
			(layer "F.Fab")
		)
		(fp_line
			(start -0.12065 0.2794)
			(end -0.12065 0.3048)
			(stroke
				(width 0.1)
				(type default)
			)
			(layer "F.Fab")
		)
		(fp_line
			(start 0.120396 0.2794)
			(end -0.12065 0.2794)
			(stroke
				(width 0.1)
				(type default)
			)
			(layer "F.Fab")
		)
		(fp_line
			(start -0.12065 -0.2794)
			(end 0.12065 -0.2794)
			(stroke
				(width 0.1)
				(type default)
			)
			(layer "F.Fab")
		)
		(fp_line
			(start 0.12065 -0.2794)
			(end 0.12065 -0.3048)
			(stroke
				(width 0.1)
				(type default)
			)
			(layer "F.Fab")
		)
		(fp_line
			(start 0.12065 -0.3048)
			(end 0.67945 -0.3048)
			(stroke
				(width 0.1)
				(type default)
			)
			(layer "F.Fab")
		)
		(fp_line
			(start 0.67945 -0.3048)
			(end 0.67945 0.3048)
			(stroke
				(width 0.1)
				(type default)
			)
			(layer "F.Fab")
		)
		(fp_line
			(start -0.67945 -0.305054)
			(end -0.12065 -0.305054)
			(stroke
				(width 0.1)
				(type default)
			)
			(layer "F.Fab")
		)
		(fp_line
			(start -0.12065 -0.305054)
			(end -0.12065 -0.2794)
			(stroke
				(width 0.1)
				(type default)
			)
			(layer "F.Fab")
		)
		(pad "1" smd circle
			(at -0.40005 0 270)
			(size 0 0)
			(layers "F.Cu" "F.Mask" "F.Paste")
			(net "I2C0_PEX1_SHPC_SCL")
		)
		(pad "2" smd circle
			(at 0.40005 0 270)
			(size 0 0)
			(layers "F.Cu" "F.Mask" "F.Paste")
			(net "I2C_PEX1_HOST_SCL")
		)
	)
	(footprint ""
		(layer "F.Cu")
		(at 390.73074 -350.098614 90)
		(property "Reference" "C759"
			(at 0 0 90)
			(layer "F.SilkS")
			(hide yes)
			(effects
				(font
					(size 1.27 1.27)
				)
			)
		)
		(property "Value" ""
			(at 0 0 90)
			(layer "F.Fab")
			(effects
				(font
					(size 1.27 1.27)
				)
			)
		)
		(duplicate_pad_numbers_are_jumpers no)
		(fp_line
			(start 0.299974 -0.150114)
			(end 0.299974 0.150114)
			(stroke
				(width 0.1)
				(type default)
			)
			(layer "F.Fab")
		)
		(fp_line
			(start -0.299974 -0.150114)
			(end 0.299974 -0.150114)
			(stroke
				(width 0.1)
				(type default)
			)
			(layer "F.Fab")
		)
		(fp_line
			(start 0.299974 0.150114)
			(end -0.299974 0.150114)
			(stroke
				(width 0.1)
				(type default)
			)
			(layer "F.Fab")
		)
		(fp_line
			(start -0.299974 0.150114)
			(end -0.299974 -0.150114)
			(stroke
				(width 0.1)
				(type default)
			)
			(layer "F.Fab")
		)
		(pad "1" smd rect
			(at -0.2667 0 90)
			(size 0.3048 0.381)
			(layers "F.Cu" "F.Mask" "F.Paste")
			(net "P5E_PEX3_STN5_TX_DN<81>")
		)
		(pad "2" smd rect
			(at 0.2667 0 90)
			(size 0.3048 0.381)
			(layers "F.Cu" "F.Mask" "F.Paste")
			(net "P5E_PEX3_STN5_TX_C_DN<81>")
		)
	)
	(footprint ""
		(layer "F.Cu")
		(at 328.022204 -356.244906 90)
		(property "Reference" "C533"
			(at 0 0 90)
			(layer "F.SilkS")
			(hide yes)
			(effects
				(font
					(size 1.27 1.27)
				)
			)
		)
		(property "Value" ""
			(at 0 0 90)
			(layer "F.Fab")
			(effects
				(font
					(size 1.27 1.27)
				)
			)
		)
		(duplicate_pad_numbers_are_jumpers no)
		(fp_line
			(start 0.299974 -0.150114)
			(end 0.299974 0.150114)
			(stroke
				(width 0.1)
				(type default)
			)
			(layer "F.Fab")
		)
		(fp_line
			(start -0.299974 -0.150114)
			(end 0.299974 -0.150114)
			(stroke
				(width 0.1)
				(type default)
			)
			(layer "F.Fab")
		)
		(fp_line
			(start 0.299974 0.150114)
			(end -0.299974 0.150114)
			(stroke
				(width 0.1)
				(type default)
			)
			(layer "F.Fab")
		)
		(fp_line
			(start -0.299974 0.150114)
			(end -0.299974 -0.150114)
			(stroke
				(width 0.1)
				(type default)
			)
			(layer "F.Fab")
		)
		(pad "1" smd rect
			(at -0.2667 0 90)
			(size 0.3048 0.381)
			(layers "F.Cu" "F.Mask" "F.Paste")
			(net "P5E_PEX2_STN5_TX_DP<88>")
		)
		(pad "2" smd rect
			(at 0.2667 0 90)
			(size 0.3048 0.381)
			(layers "F.Cu" "F.Mask" "F.Paste")
			(net "P5E_PEX2_STN5_TX_C_DP<88>")
		)
	)
	(footprint ""
		(layer "F.Cu")
		(at 369.495578 -84.927694 180)
		(property "Reference" "R1605"
			(at 0 0 180)
			(layer "F.SilkS")
			(hide yes)
			(effects
				(font
					(size 1.27 1.27)
				)
			)
		)
		(property "Value" ""
			(at 0 0 180)
			(layer "F.Fab")
			(effects
				(font
					(size 1.27 1.27)
				)
			)
		)
		(duplicate_pad_numbers_are_jumpers no)
		(fp_line
			(start 0.7874 0.4064)
			(end -0.7874 0.4064)
			(stroke
				(width 0.1524)
				(type default)
			)
			(layer "F.SilkS")
		)
		(fp_line
			(start 0.7874 -0.4064)
			(end 0.7874 0.4064)
			(stroke
				(width 0.1524)
				(type default)
			)
			(layer "F.SilkS")
		)
		(fp_line
			(start -0.7874 0.4064)
			(end -0.7874 -0.4064)
			(stroke
				(width 0.1524)
				(type default)
			)
			(layer "F.SilkS")
		)
		(fp_line
			(start -0.7874 -0.4064)
			(end 0.7874 -0.4064)
			(stroke
				(width 0.1524)
				(type default)
			)
			(layer "F.SilkS")
		)
		(fp_line
			(start 0.67945 0.3048)
			(end 0.120396 0.3048)
			(stroke
				(width 0.1)
				(type default)
			)
			(layer "F.Fab")
		)
		(fp_line
			(start 0.67945 -0.3048)
			(end 0.67945 0.3048)
			(stroke
				(width 0.1)
				(type default)
			)
			(layer "F.Fab")
		)
		(fp_line
			(start 0.12065 -0.2794)
			(end 0.12065 -0.3048)
			(stroke
				(width 0.1)
				(type default)
			)
			(layer "F.Fab")
		)
		(fp_line
			(start 0.12065 -0.3048)
			(end 0.67945 -0.3048)
			(stroke
				(width 0.1)
				(type default)
			)
			(layer "F.Fab")
		)
		(fp_line
			(start 0.120396 0.3048)
			(end 0.120396 0.2794)
			(stroke
				(width 0.1)
				(type default)
			)
			(layer "F.Fab")
		)
		(fp_line
			(start 0.120396 0.2794)
			(end -0.12065 0.2794)
			(stroke
				(width 0.1)
				(type default)
			)
			(layer "F.Fab")
		)
		(fp_line
			(start -0.12065 0.3048)
			(end -0.67945 0.3048)
			(stroke
				(width 0.1)
				(type default)
			)
			(layer "F.Fab")
		)
		(fp_line
			(start -0.12065 0.2794)
			(end -0.12065 0.3048)
			(stroke
				(width 0.1)
				(type default)
			)
			(layer "F.Fab")
		)
		(fp_line
			(start -0.12065 -0.2794)
			(end 0.12065 -0.2794)
			(stroke
				(width 0.1)
				(type default)
			)
			(layer "F.Fab")
		)
		(fp_line
			(start -0.12065 -0.305054)
			(end -0.12065 -0.2794)
			(stroke
				(width 0.1)
				(type default)
			)
			(layer "F.Fab")
		)
		(fp_line
			(start -0.67945 0.3048)
			(end -0.67945 -0.305054)
			(stroke
				(width 0.1)
				(type default)
			)
			(layer "F.Fab")
		)
		(fp_line
			(start -0.67945 -0.305054)
			(end -0.12065 -0.305054)
			(stroke
				(width 0.1)
				(type default)
			)
			(layer "F.Fab")
		)
		(pad "1" smd circle
			(at -0.40005 0 180)
			(size 0 0)
			(layers "F.Cu" "F.Mask" "F.Paste")
			(net "P3V3_AUX")
		)
		(pad "2" smd circle
			(at 0.40005 0 180)
			(size 0 0)
			(layers "F.Cu" "F.Mask" "F.Paste")
			(net "SMB_BIC_I2C9_MUX1_SSD13_R_SCL")
		)
	)
	(footprint ""
		(layer "F.Cu")
		(at 381.254 -209.55)
		(property "Reference" "R4633"
			(at 0 0 0)
			(layer "F.SilkS")
			(hide yes)
			(effects
				(font
					(size 1.27 1.27)
				)
			)
		)
		(property "Value" ""
			(at 0 0 0)
			(layer "F.Fab")
			(effects
				(font
					(size 1.27 1.27)
				)
			)
		)
		(duplicate_pad_numbers_are_jumpers no)
		(fp_line
			(start -0.7874 -0.4064)
			(end 0.7874 -0.4064)
			(stroke
				(width 0.1524)
				(type default)
			)
			(layer "F.SilkS")
		)
		(fp_line
			(start -0.7874 0.4064)
			(end -0.7874 -0.4064)
			(stroke
				(width 0.1524)
				(type default)
			)
			(layer "F.SilkS")
		)
		(fp_line
			(start 0.7874 -0.4064)
			(end 0.7874 0.4064)
			(stroke
				(width 0.1524)
				(type default)
			)
			(layer "F.SilkS")
		)
		(fp_line
			(start 0.7874 0.4064)
			(end -0.7874 0.4064)
			(stroke
				(width 0.1524)
				(type default)
			)
			(layer "F.SilkS")
		)
		(fp_line
			(start -0.67945 -0.305054)
			(end -0.12065 -0.305054)
			(stroke
				(width 0.1)
				(type default)
			)
			(layer "F.Fab")
		)
		(fp_line
			(start -0.67945 0.3048)
			(end -0.67945 -0.305054)
			(stroke
				(width 0.1)
				(type default)
			)
			(layer "F.Fab")
		)
		(fp_line
			(start -0.12065 -0.305054)
			(end -0.12065 -0.2794)
			(stroke
				(width 0.1)
				(type default)
			)
			(layer "F.Fab")
		)
		(fp_line
			(start -0.12065 -0.2794)
			(end 0.12065 -0.2794)
			(stroke
				(width 0.1)
				(type default)
			)
			(layer "F.Fab")
		)
		(fp_line
			(start -0.12065 0.2794)
			(end -0.12065 0.3048)
			(stroke
				(width 0.1)
				(type default)
			)
			(layer "F.Fab")
		)
		(fp_line
			(start -0.12065 0.3048)
			(end -0.67945 0.3048)
			(stroke
				(width 0.1)
				(type default)
			)
			(layer "F.Fab")
		)
		(fp_line
			(start 0.120396 0.2794)
			(end -0.12065 0.2794)
			(stroke
				(width 0.1)
				(type default)
			)
			(layer "F.Fab")
		)
		(fp_line
			(start 0.120396 0.3048)
			(end 0.120396 0.2794)
			(stroke
				(width 0.1)
				(type default)
			)
			(layer "F.Fab")
		)
		(fp_line
			(start 0.12065 -0.3048)
			(end 0.67945 -0.3048)
			(stroke
				(width 0.1)
				(type default)
			)
			(layer "F.Fab")
		)
		(fp_line
			(start 0.12065 -0.2794)
			(end 0.12065 -0.3048)
			(stroke
				(width 0.1)
				(type default)
			)
			(layer "F.Fab")
		)
		(fp_line
			(start 0.67945 -0.3048)
			(end 0.67945 0.3048)
			(stroke
				(width 0.1)
				(type default)
			)
			(layer "F.Fab")
		)
		(fp_line
			(start 0.67945 0.3048)
			(end 0.120396 0.3048)
			(stroke
				(width 0.1)
				(type default)
			)
			(layer "F.Fab")
		)
		(pad "1" smd circle
			(at -0.40005 0)
			(size 0 0)
			(layers "F.Cu" "F.Mask" "F.Paste")
			(net "RST_PEX_NIC0_PERST_N")
		)
		(pad "2" smd circle
			(at 0.40005 0)
			(size 0 0)
			(layers "F.Cu" "F.Mask" "F.Paste")
			(net "RST_PEX_NIC0_PERST_R_N")
		)
	)
)
